# TIMECARD (Time Appliance Project (Time Card)) — schematic netlist excerpt (pin names and nets, part order shuffled) for the footprints in the layout excerpt that follows; sources: Cadence DE-HDL packaged netlist, KiCad conversion of R4006-B0001-02_R01.brd

R327  RESISTOR  10KOHM 1%  pkg SMC_0402R_H016  page 25 : \1\ = XP3R3V_FPGA ; \2\ = FPGA_IO_7
C318  CAPACITOR  18PF 5%  pkg SMC_0201R  page 23 : \1\ = SG ; \2\ = UNNAMED_12_CAPACITOR_I332_2

(kicad_pcb
	(version 20260206)
	(generator "pcbnew")
	(generator_version "10.0")
	(general
		(thickness 1.6)
		(legacy_teardrops no)
	)
	(paper "A4")
	(title_block
		(title "timecard-production-celestica-r4006 — R4006-B0001-02_R01.brd")
		(comment 1 "Time Appliance Project (Time Card) / footprints 661-662 of 1113")
	)
	(layers
		(0 "F.Cu" signal "TOP")
		(4 "In1.Cu" signal "L02_GND1")
		(6 "In2.Cu" signal "L03_SIG1")
		(8 "In3.Cu" signal "L04_GND2")
		(10 "In4.Cu" signal "L05_VCC1")
		(12 "In5.Cu" signal "L06_VCC2")
		(14 "In6.Cu" signal "L07_GND3")
		(16 "In7.Cu" signal "L08_SIG2")
		(18 "In8.Cu" signal "L09_GND4")
		(2 "B.Cu" signal "BOTTOM")
		(9 "F.Adhes" user "F.Adhesive")
		(11 "B.Adhes" user "B.Adhesive")
		(13 "F.Paste" user "Package Geometry/Pastemask Top")
		(15 "B.Paste" user "Package Geometry/Pastemask Bottom")
		(5 "F.SilkS" user "Ref Des/Silkscreen Top")
		(7 "B.SilkS" user "Ref Des/Silkscreen Bottom")
		(1 "F.Mask" user "Board Geometry/Soldermask Top")
		(3 "B.Mask" user "Board Geometry/Soldermask Bottom")
		(17 "Dwgs.User" user "User.Drawings")
		(19 "Cmts.User" user "User.Comments")
		(21 "Eco1.User" user "User.Eco1")
		(23 "Eco2.User" user "User.Eco2")
		(25 "Edge.Cuts" user "Board Geometry/Outline")
		(27 "Margin" user)
		(31 "F.CrtYd" user "Package Geometry/Place Bound Top")
		(29 "B.CrtYd" user "Package Geometry/Place Bound Bottom")
		(35 "F.Fab" user "Ref Des/Assembly Top")
		(33 "B.Fab" user "Ref Des/Assembly Bottom")
	)
	(footprint ""
		(layer "F.Cu")
		(at 105.41 -64.2874 -90)
		(property "Reference" "R327"
			(at 0.0254 -2.70637 90)
			(unlocked yes)
			(layer "F.SilkS")
			(effects
				(font
					(size 0.7874 0.5842)
					(thickness 0.1524)
				)
			)
		)
		(property "Value" "VAL*"
			(at 0.02032 2.13233 270)
			(unlocked yes)
			(layer "F.Fab")
			(hide yes)
			(effects
				(font
					(size 0.7874 0.5842)
					(thickness 0.1524)
				)
			)
		)
		(property "Tolerance" "TOL*"
			(at 0.044704 3.05435 270)
			(unlocked yes)
			(layer "Cmts.User")
			(hide yes)
			(effects
				(font
					(size 0.7874 0.5842)
					(thickness 0.1524)
				)
			)
		)
		(property "User Part Number" "PARTNUM*"
			(at 0.02032 4.024884 270)
			(unlocked yes)
			(layer "Cmts.User")
			(hide yes)
			(effects
				(font
					(size 0.7874 0.5842)
					(thickness 0.1524)
				)
			)
		)
		(property "Device Type" "RESISTOR-G155-11002-01,10KOHM,A"
			(at 0.008382 1.210564 270)
			(unlocked yes)
			(layer "F.Fab")
			(hide yes)
			(effects
				(font
					(size 0.7874 0.5842)
					(thickness 0.1524)
				)
			)
		)
		(duplicate_pad_numbers_are_jumpers no)
		(fp_line
			(start -1.143 0.5588)
			(end 1.143 0.5588)
			(stroke
				(width 0.1)
				(type default)
			)
			(layer "F.SilkS")
		)
		(fp_line
			(start 1.143 0.5588)
			(end 1.143 -0.5588)
			(stroke
				(width 0.1)
				(type default)
			)
			(layer "F.SilkS")
		)
		(fp_line
			(start -1.143 -0.5588)
			(end -1.143 0.5588)
			(stroke
				(width 0.1)
				(type default)
			)
			(layer "F.SilkS")
		)
		(fp_line
			(start 1.143 -0.5588)
			(end -1.143 -0.5588)
			(stroke
				(width 0.1)
				(type default)
			)
			(layer "F.SilkS")
		)
		(fp_poly
			(pts
				(xy -1.143 0.5588) (xy 1.143 0.5588) (xy 1.143 -0.5588) (xy -1.143 -0.5588)
			)
			(stroke
				(width 0)
				(type default)
			)
			(fill no)
			(layer "F.CrtYd")
		)
		(fp_line
			(start -0.508 0.3048)
			(end 0.508 0.3048)
			(stroke
				(width 0.1)
				(type default)
			)
			(layer "F.Fab")
		)
		(fp_line
			(start 0.508 0.3048)
			(end 0.508 -0.3048)
			(stroke
				(width 0.1)
				(type default)
			)
			(layer "F.Fab")
		)
		(fp_line
			(start -0.508 -0.3048)
			(end -0.508 0.3048)
			(stroke
				(width 0.1)
				(type default)
			)
			(layer "F.Fab")
		)
		(fp_line
			(start 0.508 -0.3048)
			(end -0.508 -0.3048)
			(stroke
				(width 0.1)
				(type default)
			)
			(layer "F.Fab")
		)
		(pad "1" smd rect
			(at -0.5334 0 270)
			(size 0.7112 0.6096)
			(layers "F.Cu" "F.Mask" "F.Paste")
			(net "XP3R3V_FPGA")
		)
		(pad "2" smd rect
			(at 0.5334 0 270)
			(size 0.7112 0.6096)
			(layers "F.Cu" "F.Mask" "F.Paste")
			(net "FPGA_IO_7")
		)
		(zone
			(layer "F.Cu")
			(hatch none 0.5)
			(connect_pads
				(clearance 0)
			)
			(min_thickness 0.25)
			(keepout
				(tracks not_allowed)
				(vias allowed)
				(pads allowed)
				(copperpour not_allowed)
				(footprints allowed)
			)
			(placement
				(enabled no)
				(sheetname "")
			)
			(fill
				(thermal_gap 0.5)
				(thermal_bridge_width 0.5)
				(island_removal_mode 0)
			)
			(polygon
				(pts
					(xy 105.1052 -64.3636) (xy 105.1052 -64.2112) (xy 105.7148 -64.2112) (xy 105.7148 -64.3636)
				)
			)
		)
		(zone
			(layer "F.Cu")
			(hatch none 0.5)
			(connect_pads
				(clearance 0)
			)
			(min_thickness 0.25)
			(keepout
				(tracks allowed)
				(vias not_allowed)
				(pads allowed)
				(copperpour not_allowed)
				(footprints allowed)
			)
			(placement
				(enabled no)
				(sheetname "")
			)
			(fill
				(thermal_gap 0.5)
				(thermal_bridge_width 0.5)
				(island_removal_mode 0)
			)
			(polygon
				(pts
					(xy 105.1052 -64.3636) (xy 105.1052 -64.2112) (xy 105.7148 -64.2112) (xy 105.7148 -64.3636)
				)
			)
		)
	)
	(footprint ""
		(layer "F.Cu")
		(at 12.8524 -55.0164 180)
		(property "Reference" "C318"
			(at 2.1844 -0.19177 0)
			(unlocked yes)
			(layer "F.SilkS")
			(effects
				(font
					(size 0.7874 0.5842)
					(thickness 0.1524)
				)
			)
		)
		(property "Value" "VAL*"
			(at 0.193548 2.13614 180)
			(unlocked yes)
			(layer "F.Fab")
			(hide yes)
			(effects
				(font
					(size 0.7874 0.5842)
					(thickness 0.1524)
				)
			)
		)
		(property "User Part Number" "PARTNUM*"
			(at 0.216154 4.185666 180)
			(unlocked yes)
			(layer "Cmts.User")
			(hide yes)
			(effects
				(font
					(size 0.7874 0.5842)
					(thickness 0.1524)
				)
			)
		)
		(property "Device Type" "CAPACITOR-G104-0A180-FJ,18PF,5%"
			(at 0.184404 1.180592 180)
			(unlocked yes)
			(layer "F.Fab")
			(hide yes)
			(effects
				(font
					(size 0.7874 0.5842)
					(thickness 0.1524)
				)
			)
		)
		(property "Tolerance" "TOL*"
			(at 0.216154 3.1496 180)
			(unlocked yes)
			(layer "Cmts.User")
			(hide yes)
			(effects
				(font
					(size 0.7874 0.5842)
					(thickness 0.1524)
				)
			)
		)
		(duplicate_pad_numbers_are_jumpers no)
		(fp_line
			(start 0.671322 0.4445)
			(end -0.671322 0.4445)
			(stroke
				(width 0.1)
				(type default)
			)
			(layer "F.SilkS")
		)
		(fp_line
			(start 0.671322 -0.4445)
			(end 0.671322 0.4445)
			(stroke
				(width 0.1)
				(type default)
			)
			(layer "F.SilkS")
		)
		(fp_line
			(start -0.671322 0.4445)
			(end -0.671322 -0.4445)
			(stroke
				(width 0.1)
				(type default)
			)
			(layer "F.SilkS")
		)
		(fp_line
			(start -0.671322 -0.4445)
			(end 0.671322 -0.4445)
			(stroke
				(width 0.1)
				(type default)
			)
			(layer "F.SilkS")
		)
		(fp_rect
			(start -0.671322 0.4445)
			(end 0.671322 -0.4445)
			(stroke
				(width 0)
				(type default)
			)
			(fill no)
			(layer "F.CrtYd")
		)
		(fp_line
			(start 0.31496 0.1651)
			(end 0.31496 -0.1651)
			(stroke
				(width 0.1)
				(type default)
			)
			(layer "F.Fab")
		)
		(fp_line
			(start 0.31496 -0.1651)
			(end -0.31496 -0.1651)
			(stroke
				(width 0.1)
				(type default)
			)
			(layer "F.Fab")
		)
		(fp_line
			(start -0.31496 0.1651)
			(end 0.31496 0.1651)
			(stroke
				(width 0.1)
				(type default)
			)
			(layer "F.Fab")
		)
		(fp_line
			(start -0.31496 -0.1651)
			(end -0.31496 0.1651)
			(stroke
				(width 0.1)
				(type default)
			)
			(layer "F.Fab")
		)
		(pad "1" smd rect
			(at -0.264922 0 180)
			(size 0.3048 0.381)
			(layers "F.Cu" "F.Mask" "F.Paste")
			(net "SG")
		)
		(pad "2" smd rect
			(at 0.264922 0 180)
			(size 0.3048 0.381)
			(layers "F.Cu" "F.Mask" "F.Paste")
			(net "UNNAMED_12_CAPACITOR_I332_2")
		)
		(zone
			(layer "F.Cu")
			(hatch none 0.5)
			(connect_pads
				(clearance 0)
			)
			(min_thickness 0.25)
			(keepout
				(tracks not_allowed)
				(vias allowed)
				(pads allowed)
				(copperpour not_allowed)
				(footprints allowed)
			)
			(placement
				(enabled no)
				(sheetname "")
			)
			(fill
				(thermal_gap 0.5)
				(thermal_bridge_width 0.5)
				(island_removal_mode 0)
			)
			(polygon
				(pts
					(xy 12.964922 -55.2069) (xy 12.739878 -55.2069) (xy 12.739878 -54.8259) (xy 12.964922 -54.8259)
				)
			)
		)
		(zone
			(layer "F.Cu")
			(hatch none 0.5)
			(connect_pads
				(clearance 0)
			)
			(min_thickness 0.25)
			(keepout
				(tracks allowed)
				(vias not_allowed)
				(pads allowed)
				(copperpour not_allowed)
				(footprints allowed)
			)
			(placement
				(enabled no)
				(sheetname "")
			)
			(fill
				(thermal_gap 0.5)
				(thermal_bridge_width 0.5)
				(island_removal_mode 0)
			)
			(polygon
				(pts
					(xy 12.964922 -54.8259) (xy 12.964922 -55.2069) (xy 12.739878 -55.2069) (xy 12.739878 -54.8259)
				)
			)
		)
	)
)
